FILE_TYPE = MULTI_PHYS_TABLE;

PART 'LM75BDP_TSSOP8'
CLASS=IC

{========================================================================================}
:CLS_PN       = JEDEC_TYPE | ALT_SYMBOLS | DESCRIPTION                                                            ;
{========================================================================================}
 'G220-10215-01' = 'SOP8_118_P0256_V2'         | '(SOP8_118_P0256_V2)'          | 'IC, LM75B, I2C TEMP SENSOR, TSSOP8'
 'P222-10215-01' = 'SOP8_118_P0256_V2' | '(SOP8_118_P0256_V2)' | 'IC,LM75B,I2C TEMP SENSOR,SUPPLY VOLTAGE 3-5.5V,RESOLUTION 0.5C@9BITS,VSSOP-8'

END_PART

END.

